FILE_TYPE = CONNECTIVITY;
{Allegro Design Entry HDL 17.4-2019 S026 (4007227) 1/17/2022}
"PAGE_NUMBER" = 199;
0"NC";
1"GND\g";
2"GND\g";
3"GND\g";
4"GND\g";
5"PVDD18_S5_P1\g";
6"GND\g";
7"PVDD11_S3_P1\g";
8"GND\g";
9"GND\g";
10"GND\g";
11"GND\g";
12"GND\g";
13"GND\g";
14"GND\g";
15"GND\g";
16"GND\g";
17"GND\g";
18"GND\g";
19"GND\g";
20"GND\g";
21"GND\g";
22"GND\g";
23"VSENSE_VSS_SENSE_C_P1";
24"VSENSE_PVDD11_S3_P1_DP";
25"SMB_SCM_2_R2_SDA";
26"SMB_SCM_2_R2_SCL";
27"PVDD11_S3_P1_PMALERT_R";
28"PVDD11_S3_P1_PMSDA_R";
29"PVDD11_S3_P1_PMSCL_R";
30"GND\g";
31"NC_PVDD11_S3_P1_SVTO";
32"GND\g";
33"PVDD11_S3_P1_IMON1";
34"PVDD11_S3_P1_VCC";
35"PVDD11_S3_P1_IMON2";
36"PVDD11_S3_P1_RESET_N_R";
37"NC_PVDD11_S3_P1_IMON3";
38"NC_PVDD11_S3_P1_IMON4";
39"NC_PVDD11_S3_P1_PG1";
40"PVDD11_S3_P1_EN_R";
41"NC_PVDD11_S3_P1_PWM4";
42"NC_PVDD11_S3_P1_PWM3";
43"VSENSE_PVDD11_S3_P1_R";
44"NC_PVDD11_S3_P1_PWM7";
45"PWRGD_PVDD11_S3_P1_R";
46"PVDD11_S3_P1_PWM2";
47"PVDD11_S3_P1_VCCS";
48"PVDD11_S3_P1_VMON";
49"PVDD11_S3_P1_VINSEN";
50"PVDD11_S3_P1_TEMP0";
51"PVDD11_S3_P1_VDDIO";
52"NC_PVDD11_S3_P1_IMON7";
53"PVDD11_S3_P1_PWM1";
54"NC_PVDD11_S3_P1_PWM5";
55"NC_PVDD11_S3_P1_IMON5";
56"NC_PVDD11_S3_P1_PWM6";
57"NC_PVDD11_S3_P1_IMON6";
58"PVDD11_S3_P1_OCP_N_R";
59"GND\g";
60"PVDD11_S3_P1_ADDR_CFG";
61"PVDD11_S3_P1_TEMP1";
62"NC_PVDD11_S3_P1_PWM8";
63"NC_PVDD11_S3_P1_IMON8";
64"PVDD11_S3_P1_OCP_N";
65"PVDD11_S3_P1_EN";
66"PWRGD_PVDD11_S3_P1";
67"PVDD11_S3_P1_RESET_N";
68"PVDD11_S3_P1_PMALERT";
69"P3V3_AUX\g";
70"GND\g";
71"GND\g";
72"PVDD18_S5_P1\g";
73"P12V_AUX\g";
74"P3V3_AUX\g";
75"P3V3_AUX\g";
76"P5V_AUX\g";
%"VCC_CORE"
"1","(-7625,950)","0","pure_quanta_power","I1";
;
HDL_POWER"P5V_AUX"
CDS_LIB"pure_quanta_power";
"A"76;
%"Q_RES"
"1","(-6250,2125)","0","pure_quanta","I13";
;
LOCATION"R8010"
$SEC"1"
CDS_SEC"1"
WATTAGE"1/16W"
VALUE"0"
TOLERANCE"5%"
PACK_TYPE"0402LF"
MATERIAL"EMPTY"
CDS_LIB"pure_quanta"
PART_NUMBER"CS00002JB13";
"B"
$PN"2"58;
"A"
$PN"1"64;
%"UNIVERSAL_GND"
"1","(-6750,3500)","0","pure_quanta_power","I14";
;
CDS_LIB"pure_quanta_power"
HDL_POWER"GND";
"A"1;
%"Q_RES"
"2","(-6750,3675)","0","pure_quanta","I15";
;
LOCATION"PR288"
$SEC"1"
CDS_SEC"1"
MATERIAL"CHIP"
TOLERANCE"1%"
VALUE"49.9"
WATTAGE"1/16W"
PACK_TYPE"0402LF"
CDS_LIB"pure_quanta"
PART_NUMBER"CS04992FB07";
"A"
$PN"1"23;
"B"
$PN"2"1;
%"UNIVERSAL_GND"
"1","(-5725,275)","0","pure_quanta_power","I16";
;
CDS_LIB"pure_quanta_power"
HDL_POWER"GND";
"A"2;
%"Q_RES"
"2","(-5725,475)","0","pure_quanta","I17";
;
LOCATION"PR604"
$SEC"1"
CDS_SEC"1"
TOLERANCE"1%"
VALUE"4.99K"
WATTAGE"1/16W"
MATERIAL"EMPTY"
PACK_TYPE"0402LF"
CDS_LIB"pure_quanta"
PART_NUMBER"CS24992FB07";
"A"
$PN"1"49;
"B"
$PN"2"2;
%"Q_RES"
"1","(-6050,675)","0","pure_quanta","I18";
;
LOCATION"PR388"
$SEC"1"
CDS_SEC"1"
WATTAGE"1/16W"
MATERIAL"CHIP"
VALUE"0"
PACK_TYPE"0402LF"
TOLERANCE"5%"
CDS_LIB"pure_quanta"
PART_NUMBER"CS00002JB13";
"B"
$PN"2"49;
"A"
$PN"1"73;
%"UNIVERSAL_GND"
"1","(-5400,275)","0","pure_quanta_power","I19";
;
CDS_LIB"pure_quanta_power"
HDL_POWER"GND";
"A"3;
%"Q_RES"
"1","(-7275,850)","0","pure_quanta","I2";
;
LOCATION"PR376"
$SEC"1"
CDS_SEC"1"
MATERIAL"CHIP"
VALUE"40.2K"
PACK_TYPE"0402LF"
TOLERANCE"1%"
WATTAGE"1/16W"
CDS_LIB"pure_quanta"
PART_NUMBER"CS34022FB04";
"B"
$PN"2"48;
"A"
$PN"1"76;
%"Q_CAP"
"1","(-5400,500)","0","pure_quanta","I20";
;
LOCATION"PC8"
SEC"1"
PACK_TYPE"0402"
VOLTAGE"25V"
VALUE"0.1UF"
TOLERANCE"10%"
MATERIAL"X7R"
CDS_LIB"pure_quanta"
SEC_TYPE"0402"
PART_NUMBER"CH4104K1B00";
"B"
$PN"2"3;
"A"
$PN"1"49;
%"UNIVERSAL_GND"
"1","(-6175,1150)","0","pure_quanta_power","I21";
;
CDS_LIB"pure_quanta_power"
HDL_POWER"GND";
"A"4;
%"UNIVERSAL_GND"
"1","(-5175,475)","0","pure_quanta_power","I23";
;
CDS_LIB"pure_quanta_power"
HDL_POWER"GND";
"A"59;
%"Q_RES"
"2","(-5975,2350)","0","pure_quanta","I24";
;
LOCATION"R8011"
$SEC"1"
CDS_SEC"1"
WATTAGE"1/16W"
MATERIAL"EMPTY"
VALUE"1K"
TOLERANCE"1%"
PACK_TYPE"0402LF"
CDS_LIB"pure_quanta"
PART_NUMBER"CS21002FB06";
"A"
$PN"1"5;
"B"
$PN"2"58;
%"VCC_CORE"
"1","(-5975,2550)","0","pure_quanta_power","I25";
;
HDL_POWER"PVDD18_S5_P1"
CDS_LIB"pure_quanta_power";
"A"5;
%"UNIVERSAL_GND"
"1","(-5375,2575)","2","pure_quanta_power","I26";
;
CDS_LIB"pure_quanta_power"
HDL_POWER"GND";
"A"32;
%"Q_RES"
"1","(-6050,4075)","0","pure_quanta","I27";
;
LOCATION"PR384"
$SEC"1"
CDS_SEC"1"
TOLERANCE"5%"
MATERIAL"CHIP"
VALUE"0"
PACK_TYPE"0402LF"
WATTAGE"1/16W"
CDS_LIB"pure_quanta"
PART_NUMBER"CS00002JB13";
"B"
$PN"2"43;
"A"
$PN"1"24;
%"Q_CAP"
"1","(-5750,3950)","0","pure_quanta","I28";
;
LOCATION"PC639"
$SEC"1"
CDS_SEC"1"
PACK_TYPE"0402"
MATERIAL"X7R"
VALUE"3300PF"
VOLTAGE"50V"
TOLERANCE"10%"
CDS_LIB"pure_quanta"
PART_NUMBER"TMP_QCH2336K1B12";
"B"
$PN"2"23;
"A"
$PN"1"43;
%"Q_RES"
"2","(-6750,4250)","0","pure_quanta","I29";
;
LOCATION"PR229"
$SEC"1"
CDS_SEC"1"
VALUE"49.9"
PACK_TYPE"0402LF"
TOLERANCE"1%"
WATTAGE"1/16W"
MATERIAL"CHIP"
CDS_LIB"pure_quanta"
PART_NUMBER"CS04992FB07";
"A"
$PN"1"7;
"B"
$PN"2"24;
%"UNIVERSAL_GND"
"1","(-6950,425)","0","pure_quanta_power","I3";
;
CDS_LIB"pure_quanta_power"
HDL_POWER"GND";
"A"6;
%"VCC_CORE"
"1","(-6750,4450)","0","pure_quanta_power","I30";
;
HDL_POWER"PVDD11_S3_P1"
CDS_LIB"pure_quanta_power";
"A"7;
%"VCC_CORE"
"1","(-6600,6525)","0","pure_quanta_power","I36";
;
HDL_POWER"P3V3_AUX"
CDS_LIB"pure_quanta_power";
"A"69;
%"Q_RES"
"1","(-6200,6400)","0","pure_quanta","I37";
;
LOCATION"R8380"
$SEC"1"
CDS_SEC"1"
PACK_TYPE"0402LF"
VALUE"1K"
MATERIAL"CHIP"
WATTAGE"1/16W"
TOLERANCE"1%"
CDS_LIB"pure_quanta"
PART_NUMBER"CS21002FB06";
"B"
$PN"2"45;
"A"
$PN"1"69;
%"Q_RES"
"1","(-6050,4675)","0","pure_quanta","I38";
;
LOCATION"R8383"
$SEC"1"
CDS_SEC"1"
TOLERANCE"5%"
WATTAGE"1/16W"
MATERIAL"CHIP"
VALUE"33"
PACK_TYPE"0402LF"
CDS_LIB"pure_quanta"
PART_NUMBER"CS03302JB10";
"B"
$PN"2"27;
"A"
$PN"1"68;
%"Q_RES"
"1","(-6050,4825)","0","pure_quanta","I39";
;
LOCATION"R8382"
$SEC"1"
CDS_SEC"1"
VALUE"0"
WATTAGE"1/16W"
TOLERANCE"5%"
PACK_TYPE"0402LF"
MATERIAL"CHIP"
CDS_LIB"pure_quanta"
PART_NUMBER"CS00002JB13";
"B"
$PN"2"28;
"A"
$PN"1"25;
%"Q_CAP"
"1","(-6950,675)","0","pure_quanta","I4";
;
LOCATION"PC638"
$SEC"1"
CDS_SEC"1"
TOLERANCE"10%"
PACK_TYPE"0402"
VOLTAGE"25V"
MATERIAL"X7R"
VALUE"0.1UF"
CDS_LIB"pure_quanta"
PART_NUMBER"CH4104K1B00";
"B"
$PN"2"6;
"A"
$PN"1"48;
%"Q_RES"
"1","(-6050,4975)","0","pure_quanta","I40";
;
LOCATION"R8381"
$SEC"1"
CDS_SEC"1"
MATERIAL"CHIP"
TOLERANCE"5%"
VALUE"0"
WATTAGE"1/16W"
PACK_TYPE"0402LF"
CDS_LIB"pure_quanta"
PART_NUMBER"CS00002JB13";
"B"
$PN"2"29;
"A"
$PN"1"26;
%"UNIVERSAL_GND"
"1","(-6050,5125)","0","pure_quanta_power","I41";
;
CDS_LIB"pure_quanta_power"
HDL_POWER"GND";
"A"30;
%"Q_RES"
"1","(-5975,5975)","0","pure_quanta","I42";
;
LOCATION"R8386"
$SEC"1"
CDS_SEC"1"
PACK_TYPE"0402LF"
TOLERANCE"5%"
VALUE"0"
MATERIAL"CHIP"
WATTAGE"1/16W"
CDS_LIB"pure_quanta"
PART_NUMBER"CS00002JB13";
"B"
$PN"2"40;
"A"
$PN"1"65;
%"Q_RES"
"1","(-5975,6125)","0","pure_quanta","I43";
;
LOCATION"R8385"
$SEC"1"
CDS_SEC"1"
PACK_TYPE"0402LF"
MATERIAL"CHIP"
TOLERANCE"5%"
WATTAGE"1/16W"
VALUE"0"
CDS_LIB"pure_quanta"
PART_NUMBER"CS00002JB13";
"B"
$PN"2"45;
"A"
$PN"1"66;
%"Q_CAP"
"2","(-5300,5850)","0","pure_quanta","I44";
;
LOCATION"C642"
$SEC"1"
CDS_SEC"1"
VALUE"1000PF"
VOLTAGE"50V"
MATERIAL"X7R"
TOLERANCE"5%"
PACK_TYPE"0402"
CDS_LIB"pure_quanta"
PART_NUMBER"TMP_QCH21006JB10";
"A"
$PN"1"40;
"B"
$PN"2"70;
%"UNIVERSAL_GND"
"1","(-5075,5775)","0","pure_quanta_power","I45";
;
CDS_LIB"pure_quanta_power"
HDL_POWER"GND";
"A"70;
%"Q_CAP"
"2","(-5325,6400)","0","pure_quanta","I46";
;
LOCATION"C8641"
$SEC"1"
CDS_SEC"1"
MATERIAL"EMPTY"
VOLTAGE"50V"
PACK_TYPE"0402"
VALUE"1000PF"
TOLERANCE"5%"
CDS_LIB"pure_quanta"
PART_NUMBER"TMP_QCH21006JB10";
"A"
$PN"1"45;
"B"
$PN"2"71;
%"UNIVERSAL_GND"
"1","(-5075,6325)","0","pure_quanta_power","I47";
;
CDS_LIB"pure_quanta_power"
HDL_POWER"GND";
"A"71;
%"UNIVERSAL_GND"
"1","(-3450,450)","0","pure_quanta_power","I48";
;
CDS_LIB"pure_quanta_power"
HDL_POWER"GND";
"A"8;
%"Q_CAP"
"1","(-3450,725)","0","pure_quanta","I49";
;
LOCATION"PC643"
$SEC"1"
CDS_SEC"1"
PACK_TYPE"0402"
VOLTAGE"50V"
VALUE"470PF"
TOLERANCE"10%"
MATERIAL"X7R"
CDS_LIB"pure_quanta"
PART_NUMBER"TMP_QCH14706KB18";
"B"
$PN"2"8;
"A"
$PN"1"50;
%"UNIVERSAL_GND"
"1","(-6525,400)","0","pure_quanta_power","I5";
;
CDS_LIB"pure_quanta_power"
HDL_POWER"GND";
"A"9;
%"Q_RES"
"1","(-3125,1225)","0","pure_quanta","I51";
;
LOCATION"PR415"
$SEC"1"
CDS_SEC"1"
PACK_TYPE"0402LF"
MATERIAL"CHIP"
WATTAGE"1/16W"
TOLERANCE"5%"
VALUE"0"
CDS_LIB"pure_quanta"
PART_NUMBER"CS00002JB13";
"B"
$PN"2"10;
"A"
$PN"1"61;
%"Q_RES"
"1","(-3125,1875)","0","pure_quanta","I52";
;
LOCATION"PR409"
$SEC"1"
CDS_SEC"1"
PACK_TYPE"0402LF"
WATTAGE"1/16W"
TOLERANCE"5%"
VALUE"0"
MATERIAL"CHIP"
CDS_LIB"pure_quanta"
PART_NUMBER"CS00002JB13";
"B"
$PN"2"11;
"A"
$PN"1"63;
%"UNIVERSAL_GND"
"1","(-2675,1150)","0","pure_quanta_power","I53";
;
CDS_LIB"pure_quanta_power"
HDL_POWER"GND";
"A"10;
%"UNIVERSAL_GND"
"1","(-2675,1800)","0","pure_quanta_power","I54";
;
CDS_LIB"pure_quanta_power"
HDL_POWER"GND";
"A"11;
%"UNIVERSAL_GND"
"1","(-2125,1200)","0","pure_quanta_power","I55";
;
CDS_LIB"pure_quanta_power"
HDL_POWER"GND";
"A"12;
%"Q_RES"
"2","(-2125,1425)","0","pure_quanta","I56";
;
LOCATION"PR390"
$SEC"1"
CDS_SEC"1"
MATERIAL"EMPTY"
WATTAGE"1/16W"
TOLERANCE"5%"
VALUE"0"
PACK_TYPE"0402LF"
CDS_LIB"pure_quanta"
PART_NUMBER"CS00002JB13";
"A"
$PN"1"36;
"B"
$PN"2"12;
%"Q_RES"
"1","(-3125,2325)","0","pure_quanta","I57";
;
LOCATION"PR408"
$SEC"1"
CDS_SEC"1"
WATTAGE"1/16W"
MATERIAL"CHIP"
TOLERANCE"5%"
VALUE"0"
PACK_TYPE"0402LF"
CDS_LIB"pure_quanta"
PART_NUMBER"CS00002JB13";
"B"
$PN"2"13;
"A"
$PN"1"52;
%"Q_RES"
"1","(-3125,2775)","0","pure_quanta","I58";
;
LOCATION"PR14"
$SEC"1"
CDS_SEC"1"
WATTAGE"1/16W"
MATERIAL"CHIP"
TOLERANCE"5%"
VALUE"0"
PACK_TYPE"0402LF"
CDS_LIB"pure_quanta"
PART_NUMBER"CS00002JB13";
"B"
$PN"2"14;
"A"
$PN"1"57;
%"Q_RES"
"1","(-3125,3225)","0","pure_quanta","I59";
;
LOCATION"PR13"
$SEC"1"
CDS_SEC"1"
MATERIAL"CHIP"
WATTAGE"1/16W"
TOLERANCE"5%"
VALUE"0"
PACK_TYPE"0402LF"
CDS_LIB"pure_quanta"
PART_NUMBER"CS00002JB13";
"B"
$PN"2"15;
"A"
$PN"1"55;
%"Q_RES"
"2","(-6525,675)","0","pure_quanta","I6";
;
LOCATION"PR6"
SEC"1"
WATTAGE"1/16W"
MATERIAL"CHIP"
TOLERANCE"1%"
VALUE"10K"
PACK_TYPE"0402LF"
SEC_TYPE"0402LF"
CDS_LIB"pure_quanta"
PART_NUMBER"CS31002FB08";
"A"
$PN"1"48;
"B"
$PN"2"9;
%"Q_RES"
"1","(-3125,3675)","0","pure_quanta","I60";
;
LOCATION"PR407"
$SEC"1"
CDS_SEC"1"
VALUE"0"
WATTAGE"1/16W"
MATERIAL"CHIP"
PACK_TYPE"0402LF"
TOLERANCE"5%"
CDS_LIB"pure_quanta"
PART_NUMBER"CS00002JB13";
"B"
$PN"2"16;
"A"
$PN"1"38;
%"UNIVERSAL_GND"
"1","(-2675,2250)","0","pure_quanta_power","I61";
;
CDS_LIB"pure_quanta_power"
HDL_POWER"GND";
"A"13;
%"UNIVERSAL_GND"
"1","(-2675,2700)","0","pure_quanta_power","I62";
;
CDS_LIB"pure_quanta_power"
HDL_POWER"GND";
"A"14;
%"UNIVERSAL_GND"
"1","(-2675,3150)","0","pure_quanta_power","I63";
;
CDS_LIB"pure_quanta_power"
HDL_POWER"GND";
"A"15;
%"UNIVERSAL_GND"
"1","(-2675,3600)","0","pure_quanta_power","I64";
;
CDS_LIB"pure_quanta_power"
HDL_POWER"GND";
"A"16;
%"UNIVERSAL_GND"
"1","(-2675,4050)","0","pure_quanta_power","I65";
;
CDS_LIB"pure_quanta_power"
HDL_POWER"GND";
"A"17;
%"Q_RES"
"1","(-1650,1625)","0","pure_quanta","I66";
;
LOCATION"PR392"
$SEC"1"
CDS_SEC"1"
WATTAGE"1/16W"
MATERIAL"EMPTY"
TOLERANCE"5%"
VALUE"0"
PACK_TYPE"0402LF"
CDS_LIB"pure_quanta"
PART_NUMBER"CS00002JB13";
"B"
$PN"2"67;
"A"
$PN"1"36;
%"Q_RES"
"1","(-1700,1850)","0","pure_quanta","I67";
;
LOCATION"PR391"
$SEC"1"
CDS_SEC"1"
PACK_TYPE"0402LF"
WATTAGE"1/16W"
MATERIAL"EMPTY"
TOLERANCE"1%"
VALUE"1K"
CDS_LIB"pure_quanta"
PART_NUMBER"CS21002FB06";
"B"
$PN"2"72;
"A"
$PN"1"36;
%"VCC_CORE"
"1","(-1350,2000)","0","pure_quanta_power","I68";
;
HDL_POWER"PVDD18_S5_P1"
CDS_LIB"pure_quanta_power";
"A"72;
%"VCC_CORE"
"1","(-6275,750)","0","pure_quanta_power","I7";
;
HDL_POWER"P12V_AUX"
CDS_LIB"pure_quanta_power";
"A"73;
%"Q_RES"
"1","(-3125,4125)","0","pure_quanta","I70";
;
LOCATION"PR406"
$SEC"1"
CDS_SEC"1"
VALUE"0"
MATERIAL"CHIP"
WATTAGE"1/16W"
TOLERANCE"5%"
PACK_TYPE"0402LF"
CDS_LIB"pure_quanta"
PART_NUMBER"CS00002JB13";
"B"
$PN"2"17;
"A"
$PN"1"37;
%"UNIVERSAL_GND"
"1","(-3375,5450)","0","pure_quanta_power","I71";
;
CDS_LIB"pure_quanta_power"
HDL_POWER"GND";
"A"18;
%"Q_CAP"
"1","(-3375,5675)","0","pure_quanta","I72";
;
LOCATION"PC96"
$SEC"1"
CDS_SEC"1"
PACK_TYPE"0402"
VOLTAGE"25V"
VALUE"0.1UF"
TOLERANCE"10%"
MATERIAL"X7R"
CDS_LIB"pure_quanta"
PART_NUMBER"CH4104K1B00";
"B"
$PN"2"18;
"A"
$PN"1"47;
%"Q_CAP"
"1","(-3375,6150)","0","pure_quanta","I73";
;
LOCATION"PC95"
$SEC"1"
CDS_SEC"1"
PACK_TYPE"0402"
VOLTAGE"25V"
VALUE"0.1UF"
TOLERANCE"10%"
MATERIAL"X7R"
CDS_LIB"pure_quanta"
PART_NUMBER"CH4104K1B00";
"B"
$PN"2"19;
"A"
$PN"1"34;
%"UNIVERSAL_GND"
"1","(-3375,5900)","0","pure_quanta_power","I74";
;
CDS_LIB"pure_quanta_power"
HDL_POWER"GND";
"A"19;
%"UNIVERSAL_GND"
"1","(-3000,5450)","0","pure_quanta_power","I79";
;
CDS_LIB"pure_quanta_power"
HDL_POWER"GND";
"A"20;
%"VCC_CORE"
"1","(-6600,1850)","0","pure_quanta_power","I8";
;
HDL_POWER"P3V3_AUX"
CDS_LIB"pure_quanta_power";
"A"74;
%"Q_CAP"
"1","(-3000,5675)","0","pure_quanta","I80";
;
LOCATION"PC644"
$SEC"1"
CDS_SEC"1"
PACK_TYPE"C0402"
MATERIAL"X6S"
TOLERANCE"20%"
VALUE"10UF"
VOLTAGE"6.3V"
CDS_LIB"pure_quanta"
PART_NUMBER"CH6101MEB03";
"B"
$PN"2"20;
"A"
$PN"1"47;
%"Q_CAP"
"1","(-3000,6150)","0","pure_quanta","I81";
;
LOCATION"PC645"
$SEC"1"
CDS_SEC"1"
PACK_TYPE"C0402"
VOLTAGE"16V"
VALUE"1UF"
TOLERANCE"10%"
MATERIAL"X6S"
CDS_LIB"pure_quanta"
PART_NUMBER"CH5103KEB01";
"B"
$PN"2"21;
"A"
$PN"1"34;
%"UNIVERSAL_GND"
"1","(-3000,5950)","0","pure_quanta_power","I82";
;
CDS_LIB"pure_quanta_power"
HDL_POWER"GND";
"A"21;
%"Q_RES"
"1","(-2575,6300)","0","pure_quanta","I84";
;
LOCATION"PR393"
$SEC"1"
CDS_SEC"1"
MATERIAL"CHIP"
WATTAGE"1/16W"
TOLERANCE"1%"
VALUE"1"
PACK_TYPE"0402LF"
CDS_LIB"pure_quanta"
PART_NUMBER"CS-1002FB04";
"B"
$PN"2"75;
"A"
$PN"1"34;
%"VCC_CORE"
"1","(-2200,6400)","0","pure_quanta_power","I85";
;
HDL_POWER"P3V3_AUX"
CDS_LIB"pure_quanta_power";
"A"75;
%"RAA229621GNPHA0"
"1","(-4400,3375)","0","pure_quanta","I86";
;
LOCATION"PU54"
$SEC"1"
CDS_SEC"1"
VALUE"RAA229621GNP#HA0"
MATERIAL"IC"
PART_TYPE"SMLF"
CDS_LMAN_SYM_OUTLINE"-550,2850,500,-2850"
CDS_LIB"pure_quanta"
NEEDS_NO_SIZE"TRUE"
PART_NUMBER"ARF0TGP4003";
"CS0"
$PN"30"63;
"PWM0"
$PN"1"62;
"TEMP1"
$PN"35"61;
"EN1||ADDR_CFG"
$PN"34"60;
"TH_GND"
$PN"TH"59;
"OCP_L \B"
$PN"33"58;
"CS2"
$PN"28"57;
"PWM2"
$PN"3"56;
"CS3"
$PN"27"55;
"PWM3"
$PN"4"54;
"PWM7"
$PN"8"53;
"CS1"
$PN"29"52;
"RGND1"
$PN"31"32;
"VSEN1"
$PN"32"32;
"VDDIO"
$PN"15"51;
"TEMP0"
$PN"36"50;
"VINSEN"
$PN"38"49;
"VMON||IINSEN"
$PN"37"48;
"VCCS"
$PN"40"47;
"PWM6"
$PN"7"46;
"PG0"
$PN"12"45;
"PWM1"
$PN"2"44;
"VSEN0"
$PN"21"43;
"PWM5"
$PN"6"42;
"PWM4"
$PN"5"41;
"PMSDA"
$PN"9"28;
"RGND0"
$PN"22"23;
"EN0"
$PN"13"40;
"NPMALERT \B"
$PN"11"27;
"SVD"
$PN"17"30;
"PG1"
$PN"16"39;
"CS4"
$PN"26"38;
"CS5"
$PN"25"37;
"RESET_L \B"
$PN"14"36;
"SVTO"
$PN"19"31;
"CS6"
$PN"24"35;
"SVC"
$PN"18"30;
"PMSCL"
$PN"10"29;
"SVTI"
$PN"20"30;
"VCC"
$PN"39"34;
"CS7"
$PN"23"33;
%"UNIVERSAL_GND"
"1","(-6375,4300)","0","pure_quanta_power","I87";
;
CDS_LIB"pure_quanta_power"
HDL_POWER"GND";
"A"22;
%"Q_CAP"
"1","(-6375,4500)","0","pure_quanta","I88";
;
LOCATION"C5010"
$SEC"1"
CDS_SEC"1"
VOLTAGE"50V"
TOLERANCE"5%"
VALUE"1000PF"
MATERIAL"X7R"
PACK_TYPE"0402"
CDS_LIB"pure_quanta"
PART_NUMBER"TMP_QCH21006JB10";
"B"
$PN"2"22;
"A"
$PN"1"68;
%"Q_RES"
"1","(-5900,1425)","0","pure_quanta","I89";
;
LOCATION"PR464"
$SEC"1"
CDS_SEC"1"
VALUE"13.7K"
WATTAGE"1/16W"
TOLERANCE"1%"
MATERIAL"CHIP"
PACK_TYPE"0402LF"
CDS_LIB"pure_quanta"
PART_NUMBER"CS31372FB03";
"B"
$PN"2"60;
"A"
$PN"1"4;
%"Q_RES"
"1","(-6175,1725)","0","pure_quanta","I9";
;
LOCATION"R8146"
$SEC"1"
CDS_SEC"1"
TOLERANCE"5%"
WATTAGE"1/16W"
MATERIAL"EMPTY"
PACK_TYPE"0402LF"
VALUE"0"
CDS_LIB"pure_quanta"
PART_NUMBER"CS00002JB13";
"B"
$PN"2"51;
"A"
$PN"1"74;
END.
